(kicad_pcb
	(version 20260206)
	(generator "pcbnew")
	(generator_version "10.0")
	(general
		(thickness 1.6)
		(legacy_teardrops no)
	)
	(paper "A4")
	(title_block
		(title "Wiwynn_Tioga_Pass_MB.brd")
		(comment 1 "Tioga Pass / footprints 3291-3297 of 4770")
	)
	(layers
		(0 "F.Cu" signal "TOP")
		(4 "In1.Cu" signal "L2GND")
		(6 "In2.Cu" signal "L3")
		(8 "In3.Cu" signal "L4GND")
		(10 "In4.Cu" signal "L5")
		(12 "In5.Cu" signal "L6GND")
		(14 "In6.Cu" signal "L7VCC")
		(16 "In7.Cu" signal "L8VCC")
		(18 "In8.Cu" signal "L9GND")
		(20 "In9.Cu" signal "L10")
		(22 "In10.Cu" signal "L11GND")
		(24 "In11.Cu" signal "L12")
		(26 "In12.Cu" signal "L13GND")
		(2 "B.Cu" signal "BOTTOM")
		(9 "F.Adhes" user "F.Adhesive")
		(11 "B.Adhes" user "B.Adhesive")
		(13 "F.Paste" user "Package Geometry/Pastemask Top")
		(15 "B.Paste" user "Package Geometry/Pastemask Bottom")
		(5 "F.SilkS" user "Ref Des/Silkscreen Top")
		(7 "B.SilkS" user "Ref Des/Silkscreen Bottom")
		(1 "F.Mask" user "Board Geometry/Soldermask Top")
		(3 "B.Mask" user "Board Geometry/Soldermask Bottom")
		(17 "Dwgs.User" user "User.Drawings")
		(19 "Cmts.User" user "User.Comments")
		(21 "Eco1.User" user "User.Eco1")
		(23 "Eco2.User" user "User.Eco2")
		(25 "Edge.Cuts" user "Board Geometry/Outline")
		(27 "Margin" user)
		(31 "F.CrtYd" user "Package Geometry/Place Bound Top")
		(29 "B.CrtYd" user "Package Geometry/Place Bound Bottom")
		(35 "F.Fab" user "Ref Des/Assembly Top")
		(33 "B.Fab" user "Ref Des/Assembly Bottom")
	)
	(footprint ""
		(layer "B.Cu")
		(at 393.286234 -151.84374 90)
		(property "Reference" "C2L11"
			(at 0 0 90)
			(layer "B.SilkS")
			(hide yes)
			(effects
				(font
					(size 1.27 1.27)
				)
				(justify mirror)
			)
		)
		(property "Value" ""
			(at 0 0 90)
			(layer "B.Fab")
			(effects
				(font
					(size 1.27 1.27)
				)
				(justify mirror)
			)
		)
		(duplicate_pad_numbers_are_jumpers no)
		(fp_poly
			(pts
				(xy -0.3048 -0.1016) (xy -0.3048 0.9906) (xy 0.3048 0.9906) (xy 0.3048 -0.1016)
			)
			(stroke
				(width 0)
				(type default)
			)
			(fill no)
			(layer "B.CrtYd")
		)
		(fp_line
			(start 0.3048 -0.1016)
			(end 0.3048 0.9906)
			(stroke
				(width 0.1)
				(type default)
			)
			(layer "B.Fab")
		)
		(fp_line
			(start -0.3048 -0.1016)
			(end 0.3048 -0.1016)
			(stroke
				(width 0.1)
				(type default)
			)
			(layer "B.Fab")
		)
		(fp_line
			(start 0.3048 0.9906)
			(end -0.3048 0.9906)
			(stroke
				(width 0.1)
				(type default)
			)
			(layer "B.Fab")
		)
		(fp_line
			(start -0.3048 0.9906)
			(end -0.3048 -0.1016)
			(stroke
				(width 0.1)
				(type default)
			)
			(layer "B.Fab")
		)
		(pad "1" smd rect
			(at 0 0 270)
			(size 0.508 0.508)
			(layers "B.Cu" "B.Mask" "B.Paste")
			(net "VR_PVNN_PCH_VDD")
		)
		(pad "2" smd rect
			(at 0 0.889 270)
			(size 0.508 0.508)
			(layers "B.Cu" "B.Mask" "B.Paste")
			(net "GND")
		)
		(zone
			(layer "B.Cu")
			(hatch none 0.5)
			(connect_pads
				(clearance 0)
			)
			(min_thickness 0.25)
			(keepout
				(tracks allowed)
				(vias not_allowed)
				(pads allowed)
				(copperpour not_allowed)
				(footprints allowed)
			)
			(placement
				(enabled no)
				(sheetname "")
			)
			(fill
				(thermal_gap 0.5)
				(thermal_bridge_width 0.5)
				(island_removal_mode 0)
			)
			(polygon
				(pts
					(xy 393.540234 -152.09774) (xy 393.540234 -151.58974) (xy 393.921234 -151.58974) (xy 393.921234 -152.09774)
				)
			)
		)
		(zone
			(layer "B.Cu")
			(hatch none 0.5)
			(connect_pads
				(clearance 0)
			)
			(min_thickness 0.25)
			(keepout
				(tracks not_allowed)
				(vias allowed)
				(pads allowed)
				(copperpour not_allowed)
				(footprints allowed)
			)
			(placement
				(enabled no)
				(sheetname "")
			)
			(fill
				(thermal_gap 0.5)
				(thermal_bridge_width 0.5)
				(island_removal_mode 0)
			)
			(polygon
				(pts
					(xy 393.921234 -152.09774) (xy 393.921234 -151.58974) (xy 393.540234 -151.58974) (xy 393.540234 -152.09774)
				)
			)
		)
	)
	(footprint ""
		(layer "B.Cu")
		(at 378.0028 -137.8458 -90)
		(property "Reference" "C3M17"
			(at 0 0 90)
			(layer "B.SilkS")
			(hide yes)
			(effects
				(font
					(size 1.27 1.27)
				)
				(justify mirror)
			)
		)
		(property "Value" ""
			(at 0 0 90)
			(layer "B.Fab")
			(effects
				(font
					(size 1.27 1.27)
				)
				(justify mirror)
			)
		)
		(duplicate_pad_numbers_are_jumpers no)
		(fp_poly
			(pts
				(xy 0.4953 -0.2032) (xy -0.4953 -0.2032) (xy -0.4953 1.6002) (xy 0.4953 1.6002)
			)
			(stroke
				(width 0)
				(type default)
			)
			(fill no)
			(layer "B.CrtYd")
		)
		(fp_line
			(start -0.4953 1.6002)
			(end 0.4953 1.6002)
			(stroke
				(width 0.1)
				(type default)
			)
			(layer "B.Fab")
		)
		(fp_line
			(start 0.4953 1.6002)
			(end 0.4953 -0.2032)
			(stroke
				(width 0.1)
				(type default)
			)
			(layer "B.Fab")
		)
		(fp_line
			(start -0.4953 -0.2032)
			(end -0.4953 1.6002)
			(stroke
				(width 0.1)
				(type default)
			)
			(layer "B.Fab")
		)
		(fp_line
			(start 0.4953 -0.2032)
			(end -0.4953 -0.2032)
			(stroke
				(width 0.1)
				(type default)
			)
			(layer "B.Fab")
		)
		(pad "1" smd rect
			(at 0 0 90)
			(size 0.762 0.889)
			(layers "B.Cu" "B.Mask" "B.Paste")
			(net "P1V05_PCH_STBY_VCCA_PLL1")
		)
		(pad "2" smd rect
			(at 0 1.397 90)
			(size 0.762 0.889)
			(layers "B.Cu" "B.Mask" "B.Paste")
			(net "GND")
		)
		(zone
			(layer "B.Cu")
			(hatch none 0.5)
			(connect_pads
				(clearance 0)
			)
			(min_thickness 0.25)
			(keepout
				(tracks not_allowed)
				(vias allowed)
				(pads allowed)
				(copperpour not_allowed)
				(footprints allowed)
			)
			(placement
				(enabled no)
				(sheetname "")
			)
			(fill
				(thermal_gap 0.5)
				(thermal_bridge_width 0.5)
				(island_removal_mode 0)
			)
			(polygon
				(pts
					(xy 377.5583 -137.4648) (xy 377.5583 -138.2268) (xy 377.0503 -138.2268) (xy 377.0503 -137.4648)
				)
			)
		)
	)
	(footprint ""
		(layer "B.Cu")
		(at 375.0564 -131.9784 180)
		(property "Reference" "C3M29"
			(at 0 0 0)
			(layer "B.SilkS")
			(hide yes)
			(effects
				(font
					(size 1.27 1.27)
				)
				(justify mirror)
			)
		)
		(property "Value" ""
			(at 0 0 0)
			(layer "B.Fab")
			(effects
				(font
					(size 1.27 1.27)
				)
				(justify mirror)
			)
		)
		(duplicate_pad_numbers_are_jumpers no)
		(fp_poly
			(pts
				(xy -0.3048 -0.1016) (xy -0.3048 0.9906) (xy 0.3048 0.9906) (xy 0.3048 -0.1016)
			)
			(stroke
				(width 0)
				(type default)
			)
			(fill no)
			(layer "B.CrtYd")
		)
		(fp_line
			(start 0.3048 0.9906)
			(end -0.3048 0.9906)
			(stroke
				(width 0.1)
				(type default)
			)
			(layer "B.Fab")
		)
		(fp_line
			(start 0.3048 -0.1016)
			(end 0.3048 0.9906)
			(stroke
				(width 0.1)
				(type default)
			)
			(layer "B.Fab")
		)
		(fp_line
			(start -0.3048 0.9906)
			(end -0.3048 -0.1016)
			(stroke
				(width 0.1)
				(type default)
			)
			(layer "B.Fab")
		)
		(fp_line
			(start -0.3048 -0.1016)
			(end 0.3048 -0.1016)
			(stroke
				(width 0.1)
				(type default)
			)
			(layer "B.Fab")
		)
		(pad "1" smd rect
			(at 0 0)
			(size 0.508 0.508)
			(layers "B.Cu" "B.Mask" "B.Paste")
			(net "P1V05_PCH_STBY_ISCLK_PLL")
		)
		(pad "2" smd rect
			(at 0 0.889)
			(size 0.508 0.508)
			(layers "B.Cu" "B.Mask" "B.Paste")
			(net "GND")
		)
		(zone
			(layer "B.Cu")
			(hatch none 0.5)
			(connect_pads
				(clearance 0)
			)
			(min_thickness 0.25)
			(keepout
				(tracks not_allowed)
				(vias allowed)
				(pads allowed)
				(copperpour not_allowed)
				(footprints allowed)
			)
			(placement
				(enabled no)
				(sheetname "")
			)
			(fill
				(thermal_gap 0.5)
				(thermal_bridge_width 0.5)
				(island_removal_mode 0)
			)
			(polygon
				(pts
					(xy 374.8024 -132.6134) (xy 375.3104 -132.6134) (xy 375.3104 -132.2324) (xy 374.8024 -132.2324)
				)
			)
		)
		(zone
			(layer "B.Cu")
			(hatch none 0.5)
			(connect_pads
				(clearance 0)
			)
			(min_thickness 0.25)
			(keepout
				(tracks allowed)
				(vias not_allowed)
				(pads allowed)
				(copperpour not_allowed)
				(footprints allowed)
			)
			(placement
				(enabled no)
				(sheetname "")
			)
			(fill
				(thermal_gap 0.5)
				(thermal_bridge_width 0.5)
				(island_removal_mode 0)
			)
			(polygon
				(pts
					(xy 374.8024 -132.2324) (xy 375.3104 -132.2324) (xy 375.3104 -132.6134) (xy 374.8024 -132.6134)
				)
			)
		)
	)
	(footprint ""
		(layer "B.Cu")
		(at 405.44496 -50.9397 90)
		(property "Reference" "R25W144"
			(at 0.8382 -0.67818 90)
			(unlocked yes)
			(layer "B.SilkS")
			(effects
				(font
					(size 0.4064 0.254)
					(thickness 0.1524)
				)
				(justify left mirror)
			)
		)
		(property "Value" ""
			(at 0 0 90)
			(layer "B.Fab")
			(effects
				(font
					(size 1.27 1.27)
				)
				(justify mirror)
			)
		)
		(duplicate_pad_numbers_are_jumpers no)
		(fp_poly
			(pts
				(xy 0.2794 -0.1016) (xy -0.2794 -0.1016) (xy -0.2794 0.9906) (xy 0.2794 0.9906)
			)
			(stroke
				(width 0)
				(type default)
			)
			(fill no)
			(layer "B.CrtYd")
		)
		(fp_line
			(start 0.2794 -0.1016)
			(end 0.2794 0.9906)
			(stroke
				(width 0.1)
				(type default)
			)
			(layer "B.Fab")
		)
		(fp_line
			(start -0.2794 -0.1016)
			(end 0.2794 -0.1016)
			(stroke
				(width 0.1)
				(type default)
			)
			(layer "B.Fab")
		)
		(fp_line
			(start 0.2794 0.9906)
			(end -0.2794 0.9906)
			(stroke
				(width 0.1)
				(type default)
			)
			(layer "B.Fab")
		)
		(fp_line
			(start -0.2794 0.9906)
			(end -0.2794 -0.1016)
			(stroke
				(width 0.1)
				(type default)
			)
			(layer "B.Fab")
		)
		(pad "1" smd rect
			(at 0 0 270)
			(size 0.508 0.508)
			(layers "B.Cu" "B.Mask" "B.Paste")
			(net "FM_PWR_BTN_R1_N")
		)
		(pad "2" smd rect
			(at 0 0.889 270)
			(size 0.508 0.508)
			(layers "B.Cu" "B.Mask" "B.Paste")
			(net "FM_PWR_BTN_N")
		)
		(zone
			(layer "B.Cu")
			(hatch none 0.5)
			(connect_pads
				(clearance 0)
			)
			(min_thickness 0.25)
			(keepout
				(tracks allowed)
				(vias not_allowed)
				(pads allowed)
				(copperpour not_allowed)
				(footprints allowed)
			)
			(placement
				(enabled no)
				(sheetname "")
			)
			(fill
				(thermal_gap 0.5)
				(thermal_bridge_width 0.5)
				(island_removal_mode 0)
			)
			(polygon
				(pts
					(xy 405.69896 -51.1937) (xy 405.69896 -50.6857) (xy 406.07996 -50.6857) (xy 406.07996 -51.1937)
				)
			)
		)
		(zone
			(layer "B.Cu")
			(hatch none 0.5)
			(connect_pads
				(clearance 0)
			)
			(min_thickness 0.25)
			(keepout
				(tracks not_allowed)
				(vias allowed)
				(pads allowed)
				(copperpour not_allowed)
				(footprints allowed)
			)
			(placement
				(enabled no)
				(sheetname "")
			)
			(fill
				(thermal_gap 0.5)
				(thermal_bridge_width 0.5)
				(island_removal_mode 0)
			)
			(polygon
				(pts
					(xy 406.07996 -51.1937) (xy 406.07996 -50.6857) (xy 405.69896 -50.6857) (xy 405.69896 -51.1937)
				)
			)
		)
	)
	(footprint ""
		(layer "B.Cu")
		(at 442.9506 -22.3393 90)
		(property "Reference" "R3W4"
			(at 0 0 90)
			(layer "B.SilkS")
			(hide yes)
			(effects
				(font
					(size 1.27 1.27)
				)
				(justify mirror)
			)
		)
		(property "Value" "*"
			(at -0.064008 -4.108196 90)
			(unlocked yes)
			(layer "B.Fab")
			(hide yes)
			(effects
				(font
					(size 1.27 1.016)
					(thickness 0.1524)
				)
				(justify mirror)
			)
		)
		(property "Device Type" "47KR2F-GP_RCL_GP-47KR2F-GP,64.A"
			(at -0.064008 -5.632196 90)
			(unlocked yes)
			(layer "B.Fab")
			(hide yes)
			(effects
				(font
					(size 1.27 1.016)
					(thickness 0.1524)
				)
				(justify mirror)
			)
		)
		(duplicate_pad_numbers_are_jumpers no)
		(fp_line
			(start 0.508 -0.9398)
			(end 0.508 0.9398)
			(stroke
				(width 0.1524)
				(type default)
			)
			(layer "B.SilkS")
		)
		(fp_line
			(start -0.508 -0.9398)
			(end 0.508 -0.9398)
			(stroke
				(width 0.1524)
				(type default)
			)
			(layer "B.SilkS")
		)
		(fp_rect
			(start 0.508 0.9398)
			(end -0.508 -0.9398)
			(stroke
				(width 0)
				(type default)
			)
			(fill no)
			(layer "B.CrtYd")
		)
		(fp_rect
			(start 0.508 0.9398)
			(end -0.508 -0.9398)
			(stroke
				(width 0)
				(type default)
			)
			(fill no)
			(layer "B.Fab")
		)
		(pad "1" smd custom
			(at 0 -0.4445 270)
			(size 0.1397 0.1397)
			(layers "B.Cu" "B.Mask" "B.Paste")
			(net "FM_TPM_PRES_RST_N")
			(options
				(clearance outline)
				(anchor circle)
			)
			(primitives
				(gr_poly
					(pts
						(arc
							(start -0.1778 0.2794)
							(mid -0.249642 0.249642)
							(end -0.2794 0.1778)
						)
						(arc
							(start -0.2794 -0.1778)
							(mid -0.249642 -0.249642)
							(end -0.1778 -0.2794)
						)
						(arc
							(start 0.1778 -0.2794)
							(mid 0.249642 -0.249642)
							(end 0.2794 -0.1778)
						)
						(arc
							(start 0.2794 0.1778)
							(mid 0.249642 0.249642)
							(end 0.1778 0.2794)
						)
					)
					(width 0)
					(fill yes)
				)
			)
		)
		(pad "2" smd custom
			(at 0 0.4445 270)
			(size 0.1397 0.1397)
			(layers "B.Cu" "B.Mask" "B.Paste")
			(net "FM_TPM_PRES_RST_N_R")
			(options
				(clearance outline)
				(anchor circle)
			)
			(primitives
				(gr_poly
					(pts
						(arc
							(start -0.1778 0.2794)
							(mid -0.249642 0.249642)
							(end -0.2794 0.1778)
						)
						(arc
							(start -0.2794 -0.1778)
							(mid -0.249642 -0.249642)
							(end -0.1778 -0.2794)
						)
						(arc
							(start 0.1778 -0.2794)
							(mid 0.249642 -0.249642)
							(end 0.2794 -0.1778)
						)
						(arc
							(start 0.2794 0.1778)
							(mid 0.249642 0.249642)
							(end 0.1778 0.2794)
						)
					)
					(width 0)
					(fill yes)
				)
			)
		)
	)
	(footprint ""
		(layer "B.Cu")
		(at 401.701 -34.798 90)
		(property "Reference" "R25W106"
			(at 0.8382 -0.67818 90)
			(unlocked yes)
			(layer "B.SilkS")
			(effects
				(font
					(size 0.4064 0.254)
					(thickness 0.1524)
				)
				(justify left mirror)
			)
		)
		(property "Value" ""
			(at 0 0 90)
			(layer "B.Fab")
			(effects
				(font
					(size 1.27 1.27)
				)
				(justify mirror)
			)
		)
		(duplicate_pad_numbers_are_jumpers no)
		(fp_poly
			(pts
				(xy 0.2794 -0.1016) (xy -0.2794 -0.1016) (xy -0.2794 0.9906) (xy 0.2794 0.9906)
			)
			(stroke
				(width 0)
				(type default)
			)
			(fill no)
			(layer "B.CrtYd")
		)
		(fp_line
			(start 0.2794 -0.1016)
			(end 0.2794 0.9906)
			(stroke
				(width 0.1)
				(type default)
			)
			(layer "B.Fab")
		)
		(fp_line
			(start -0.2794 -0.1016)
			(end 0.2794 -0.1016)
			(stroke
				(width 0.1)
				(type default)
			)
			(layer "B.Fab")
		)
		(fp_line
			(start 0.2794 0.9906)
			(end -0.2794 0.9906)
			(stroke
				(width 0.1)
				(type default)
			)
			(layer "B.Fab")
		)
		(fp_line
			(start -0.2794 0.9906)
			(end -0.2794 -0.1016)
			(stroke
				(width 0.1)
				(type default)
			)
			(layer "B.Fab")
		)
		(pad "1" smd rect
			(at 0 0 270)
			(size 0.508 0.508)
			(layers "B.Cu" "B.Mask" "B.Paste")
			(net "P3V3_STBY")
		)
		(pad "2" smd rect
			(at 0 0.889 270)
			(size 0.508 0.508)
			(layers "B.Cu" "B.Mask" "B.Paste")
			(net "RMII_BMC_OCP_TXEN")
		)
		(zone
			(layer "B.Cu")
			(hatch none 0.5)
			(connect_pads
				(clearance 0)
			)
			(min_thickness 0.25)
			(keepout
				(tracks allowed)
				(vias not_allowed)
				(pads allowed)
				(copperpour not_allowed)
				(footprints allowed)
			)
			(placement
				(enabled no)
				(sheetname "")
			)
			(fill
				(thermal_gap 0.5)
				(thermal_bridge_width 0.5)
				(island_removal_mode 0)
			)
			(polygon
				(pts
					(xy 401.955 -35.052) (xy 401.955 -34.544) (xy 402.336 -34.544) (xy 402.336 -35.052)
				)
			)
		)
		(zone
			(layer "B.Cu")
			(hatch none 0.5)
			(connect_pads
				(clearance 0)
			)
			(min_thickness 0.25)
			(keepout
				(tracks not_allowed)
				(vias allowed)
				(pads allowed)
				(copperpour not_allowed)
				(footprints allowed)
			)
			(placement
				(enabled no)
				(sheetname "")
			)
			(fill
				(thermal_gap 0.5)
				(thermal_bridge_width 0.5)
				(island_removal_mode 0)
			)
			(polygon
				(pts
					(xy 402.336 -35.052) (xy 402.336 -34.544) (xy 401.955 -34.544) (xy 401.955 -35.052)
				)
			)
		)
	)
	(footprint ""
		(layer "B.Cu")
		(at 278.576024 -69.809614 -90)
		(property "Reference" "C4P10"
			(at 0 0 90)
			(layer "B.SilkS")
			(hide yes)
			(effects
				(font
					(size 1.27 1.27)
				)
				(justify mirror)
			)
		)
		(property "Value" ""
			(at 0 0 90)
			(layer "B.Fab")
			(effects
				(font
					(size 1.27 1.27)
				)
				(justify mirror)
			)
		)
		(duplicate_pad_numbers_are_jumpers no)
		(fp_poly
			(pts
				(xy 0.7239 -0.2159) (xy -0.7239 -0.2159) (xy -0.7239 1.9939) (xy 0.7239 1.9939)
			)
			(stroke
				(width 0)
				(type default)
			)
			(fill no)
			(layer "B.CrtYd")
		)
		(fp_line
			(start -0.7239 1.9939)
			(end -0.7239 -0.2159)
			(stroke
				(width 0.1)
				(type default)
			)
			(layer "B.Fab")
		)
		(fp_line
			(start 0.7239 1.9939)
			(end -0.7239 1.9939)
			(stroke
				(width 0.1)
				(type default)
			)
			(layer "B.Fab")
		)
		(fp_line
			(start -0.7239 -0.2159)
			(end 0.7239 -0.2159)
			(stroke
				(width 0.1)
				(type default)
			)
			(layer "B.Fab")
		)
		(fp_line
			(start 0.7239 -0.2159)
			(end 0.7239 1.9939)
			(stroke
				(width 0.1)
				(type default)
			)
			(layer "B.Fab")
		)
		(pad "1" smd rect
			(at 0 0 90)
			(size 1.27 1.016)
			(layers "B.Cu" "B.Mask" "B.Paste")
			(net "PVCCIO_CPU0")
		)
		(pad "2" smd rect
			(at 0 1.778 90)
			(size 1.27 1.016)
			(layers "B.Cu" "B.Mask" "B.Paste")
			(net "GND")
		)
		(zone
			(layer "B.Cu")
			(hatch none 0.5)
			(connect_pads
				(clearance 0)
			)
			(min_thickness 0.25)
			(keepout
				(tracks not_allowed)
				(vias allowed)
				(pads allowed)
				(copperpour not_allowed)
				(footprints allowed)
			)
			(placement
				(enabled no)
				(sheetname "")
			)
			(fill
				(thermal_gap 0.5)
				(thermal_bridge_width 0.5)
				(island_removal_mode 0)
			)
			(polygon
				(pts
					(xy 278.068024 -69.174614) (xy 278.068024 -70.444614) (xy 277.306024 -70.444614) (xy 277.306024 -69.174614)
				)
			)
		)
	)
)
